# BASEBOARD_FAB2 (Tioga Pass) — schematic netlist excerpt (pin names and nets, part order shuffled) for the footprints in the layout excerpt that follows; sources: Cadence DE-HDL packaged netlist, KiCad conversion of Wiwynn_Tioga_Pass_MB.brd

C2L7  CAP_A  0.01UF 25V 10% X7R  pkg 0402V  page 173 : A = SATA6G_PCH_PCIE_UP_SATA_RXP<7> ; B = SATA6G_P7_RX_C_DP
SH5L1  SHUNT  EMPTY  pkg SH0201  page 222 : A = VR_PVTT_DEF_SNS ; B = PVTT_DEF
C2M20  CAP_A  1.0UF 6.3V 10% X6S  pkg 0402V  page 131 : A = P1V05_PCH_STBY ; B = GND

(kicad_pcb
	(version 20260206)
	(generator "pcbnew")
	(generator_version "10.0")
	(general
		(thickness 1.6)
		(legacy_teardrops no)
	)
	(paper "A4")
	(title_block
		(title "Wiwynn_Tioga_Pass_MB.brd")
		(comment 1 "Tioga Pass / footprints 4321-4323 of 4770")
	)
	(layers
		(0 "F.Cu" signal "TOP")
		(4 "In1.Cu" signal "L2GND")
		(6 "In2.Cu" signal "L3")
		(8 "In3.Cu" signal "L4GND")
		(10 "In4.Cu" signal "L5")
		(12 "In5.Cu" signal "L6GND")
		(14 "In6.Cu" signal "L7VCC")
		(16 "In7.Cu" signal "L8VCC")
		(18 "In8.Cu" signal "L9GND")
		(20 "In9.Cu" signal "L10")
		(22 "In10.Cu" signal "L11GND")
		(24 "In11.Cu" signal "L12")
		(26 "In12.Cu" signal "L13GND")
		(2 "B.Cu" signal "BOTTOM")
		(9 "F.Adhes" user "F.Adhesive")
		(11 "B.Adhes" user "B.Adhesive")
		(13 "F.Paste" user "Package Geometry/Pastemask Top")
		(15 "B.Paste" user "Package Geometry/Pastemask Bottom")
		(5 "F.SilkS" user "Ref Des/Silkscreen Top")
		(7 "B.SilkS" user "Ref Des/Silkscreen Bottom")
		(1 "F.Mask" user "Board Geometry/Soldermask Top")
		(3 "B.Mask" user "Board Geometry/Soldermask Bottom")
		(17 "Dwgs.User" user "User.Drawings")
		(19 "Cmts.User" user "User.Comments")
		(21 "Eco1.User" user "User.Eco1")
		(23 "Eco2.User" user "User.Eco2")
		(25 "Edge.Cuts" user "Board Geometry/Outline")
		(27 "Margin" user)
		(31 "F.CrtYd" user "Package Geometry/Place Bound Top")
		(29 "B.CrtYd" user "Package Geometry/Place Bound Bottom")
		(35 "F.Fab" user "Ref Des/Assembly Top")
		(33 "B.Fab" user "Ref Des/Assembly Bottom")
	)
	(footprint ""
		(layer "B.Cu")
		(at 392.117326 -113.903252 90)
		(property "Reference" "C2M20"
			(at 0 0 90)
			(layer "B.SilkS")
			(hide yes)
			(effects
				(font
					(size 1.27 1.27)
				)
				(justify mirror)
			)
		)
		(property "Value" ""
			(at 0 0 90)
			(layer "B.Fab")
			(effects
				(font
					(size 1.27 1.27)
				)
				(justify mirror)
			)
		)
		(duplicate_pad_numbers_are_jumpers no)
		(fp_poly
			(pts
				(xy -0.3048 -0.1016) (xy -0.3048 0.9906) (xy 0.3048 0.9906) (xy 0.3048 -0.1016)
			)
			(stroke
				(width 0)
				(type default)
			)
			(fill no)
			(layer "B.CrtYd")
		)
		(fp_line
			(start 0.3048 -0.1016)
			(end 0.3048 0.9906)
			(stroke
				(width 0.1)
				(type default)
			)
			(layer "B.Fab")
		)
		(fp_line
			(start -0.3048 -0.1016)
			(end 0.3048 -0.1016)
			(stroke
				(width 0.1)
				(type default)
			)
			(layer "B.Fab")
		)
		(fp_line
			(start 0.3048 0.9906)
			(end -0.3048 0.9906)
			(stroke
				(width 0.1)
				(type default)
			)
			(layer "B.Fab")
		)
		(fp_line
			(start -0.3048 0.9906)
			(end -0.3048 -0.1016)
			(stroke
				(width 0.1)
				(type default)
			)
			(layer "B.Fab")
		)
		(pad "1" smd rect
			(at 0 0 270)
			(size 0.508 0.508)
			(layers "B.Cu" "B.Mask" "B.Paste")
			(net "P1V05_PCH_STBY")
		)
		(pad "2" smd rect
			(at 0 0.889 270)
			(size 0.508 0.508)
			(layers "B.Cu" "B.Mask" "B.Paste")
			(net "GND")
		)
		(zone
			(layer "B.Cu")
			(hatch none 0.5)
			(connect_pads
				(clearance 0)
			)
			(min_thickness 0.25)
			(keepout
				(tracks allowed)
				(vias not_allowed)
				(pads allowed)
				(copperpour not_allowed)
				(footprints allowed)
			)
			(placement
				(enabled no)
				(sheetname "")
			)
			(fill
				(thermal_gap 0.5)
				(thermal_bridge_width 0.5)
				(island_removal_mode 0)
			)
			(polygon
				(pts
					(xy 392.371326 -114.157252) (xy 392.371326 -113.649252) (xy 392.752326 -113.649252) (xy 392.752326 -114.157252)
				)
			)
		)
		(zone
			(layer "B.Cu")
			(hatch none 0.5)
			(connect_pads
				(clearance 0)
			)
			(min_thickness 0.25)
			(keepout
				(tracks not_allowed)
				(vias allowed)
				(pads allowed)
				(copperpour not_allowed)
				(footprints allowed)
			)
			(placement
				(enabled no)
				(sheetname "")
			)
			(fill
				(thermal_gap 0.5)
				(thermal_bridge_width 0.5)
				(island_removal_mode 0)
			)
			(polygon
				(pts
					(xy 392.752326 -114.157252) (xy 392.752326 -113.649252) (xy 392.371326 -113.649252) (xy 392.371326 -114.157252)
				)
			)
		)
	)
	(footprint ""
		(layer "B.Cu")
		(at 255.38938 -157.57652 90)
		(property "Reference" "SH5L1"
			(at 0 0 90)
			(layer "B.SilkS")
			(hide yes)
			(effects
				(font
					(size 1.27 1.27)
				)
				(justify mirror)
			)
		)
		(property "Value" ""
			(at 0 0 90)
			(layer "B.Fab")
			(effects
				(font
					(size 1.27 1.27)
				)
				(justify mirror)
			)
		)
		(duplicate_pad_numbers_are_jumpers no)
		(fp_poly
			(pts
				(xy 0.1651 -0.0508) (xy 0.1651 0.5842) (xy -0.1651 0.5842) (xy -0.1651 -0.0508)
			)
			(stroke
				(width 0)
				(type default)
			)
			(fill no)
			(layer "B.CrtYd")
		)
		(fp_line
			(start 0.1651 -0.0508)
			(end -0.1651 -0.0508)
			(stroke
				(width 0.1)
				(type default)
			)
			(layer "B.Fab")
		)
		(fp_line
			(start -0.1651 -0.0508)
			(end -0.1651 0.5842)
			(stroke
				(width 0.1)
				(type default)
			)
			(layer "B.Fab")
		)
		(fp_line
			(start 0.1651 0.5842)
			(end 0.1651 -0.0508)
			(stroke
				(width 0.1)
				(type default)
			)
			(layer "B.Fab")
		)
		(fp_line
			(start -0.1651 0.5842)
			(end 0.1651 0.5842)
			(stroke
				(width 0.1)
				(type default)
			)
			(layer "B.Fab")
		)
		(pad "1" smd custom
			(at 0 0 90)
			(size 0.0762 0.0762)
			(layers "B.Cu" "B.Mask" "B.Paste")
			(net "VR_PVTT_DEF_SNS")
			(options
				(clearance outline)
				(anchor circle)
			)
			(primitives
				(gr_poly
					(pts
						(arc
							(start -0.1524 0.10795)
							(mid -0.098518 0.130268)
							(end -0.0762 0.18415)
						)
						(xy -0.0762 0.22225) (xy 0.0762 0.22225)
						(arc
							(start 0.0762 0.18415)
							(mid 0.098518 0.130268)
							(end 0.1524 0.10795)
						)
						(xy 0.1524 -0.22225) (xy -0.1524 -0.22225)
					)
					(width 0)
					(fill yes)
				)
			)
		)
		(pad "2" smd custom
			(at 0 0.5334 270)
			(size 0.0762 0.0762)
			(layers "B.Cu" "B.Mask" "B.Paste")
			(net "PVTT_DEF")
			(options
				(clearance outline)
				(anchor circle)
			)
			(primitives
				(gr_poly
					(pts
						(arc
							(start -0.1524 0.10795)
							(mid -0.098518 0.130268)
							(end -0.0762 0.18415)
						)
						(xy -0.0762 0.22225) (xy 0.0762 0.22225)
						(arc
							(start 0.0762 0.18415)
							(mid 0.098518 0.130268)
							(end 0.1524 0.10795)
						)
						(xy 0.1524 -0.22225) (xy -0.1524 -0.22225)
					)
					(width 0)
					(fill yes)
				)
			)
		)
	)
	(footprint ""
		(layer "B.Cu")
		(at 408.1526 -153.5938 90)
		(property "Reference" "C2L7"
			(at 0 0 90)
			(layer "B.SilkS")
			(hide yes)
			(effects
				(font
					(size 1.27 1.27)
				)
				(justify mirror)
			)
		)
		(property "Value" ""
			(at 0 0 90)
			(layer "B.Fab")
			(effects
				(font
					(size 1.27 1.27)
				)
				(justify mirror)
			)
		)
		(duplicate_pad_numbers_are_jumpers no)
		(fp_poly
			(pts
				(xy -0.3048 -0.1016) (xy -0.3048 0.9906) (xy 0.3048 0.9906) (xy 0.3048 -0.1016)
			)
			(stroke
				(width 0)
				(type default)
			)
			(fill no)
			(layer "B.CrtYd")
		)
		(fp_line
			(start 0.3048 -0.1016)
			(end 0.3048 0.9906)
			(stroke
				(width 0.1)
				(type default)
			)
			(layer "B.Fab")
		)
		(fp_line
			(start -0.3048 -0.1016)
			(end 0.3048 -0.1016)
			(stroke
				(width 0.1)
				(type default)
			)
			(layer "B.Fab")
		)
		(fp_line
			(start 0.3048 0.9906)
			(end -0.3048 0.9906)
			(stroke
				(width 0.1)
				(type default)
			)
			(layer "B.Fab")
		)
		(fp_line
			(start -0.3048 0.9906)
			(end -0.3048 -0.1016)
			(stroke
				(width 0.1)
				(type default)
			)
			(layer "B.Fab")
		)
		(pad "1" smd rect
			(at 0 0 270)
			(size 0.508 0.508)
			(layers "B.Cu" "B.Mask" "B.Paste")
			(net "SATA6G_PCH_PCIE_UP_SATA_RXP<7>")
		)
		(pad "2" smd rect
			(at 0 0.889 270)
			(size 0.508 0.508)
			(layers "B.Cu" "B.Mask" "B.Paste")
			(net "SATA6G_P7_RX_C_DP")
		)
		(zone
			(layer "B.Cu")
			(hatch none 0.5)
			(connect_pads
				(clearance 0)
			)
			(min_thickness 0.25)
			(keepout
				(tracks allowed)
				(vias not_allowed)
				(pads allowed)
				(copperpour not_allowed)
				(footprints allowed)
			)
			(placement
				(enabled no)
				(sheetname "")
			)
			(fill
				(thermal_gap 0.5)
				(thermal_bridge_width 0.5)
				(island_removal_mode 0)
			)
			(polygon
				(pts
					(xy 408.4066 -153.8478) (xy 408.4066 -153.3398) (xy 408.7876 -153.3398) (xy 408.7876 -153.8478)
				)
			)
		)
		(zone
			(layer "B.Cu")
			(hatch none 0.5)
			(connect_pads
				(clearance 0)
			)
			(min_thickness 0.25)
			(keepout
				(tracks not_allowed)
				(vias allowed)
				(pads allowed)
				(copperpour not_allowed)
				(footprints allowed)
			)
			(placement
				(enabled no)
				(sheetname "")
			)
			(fill
				(thermal_gap 0.5)
				(thermal_bridge_width 0.5)
				(island_removal_mode 0)
			)
			(polygon
				(pts
					(xy 408.7876 -153.8478) (xy 408.7876 -153.3398) (xy 408.4066 -153.3398) (xy 408.4066 -153.8478)
				)
			)
		)
	)
)
